# S9S_MB_2U (Grand Teton) — schematic netlist excerpt (pin names and nets, part order shuffled) for the footprints in the layout excerpt that follows; sources: Cadence DE-HDL packaged netlist, KiCad conversion of 03242023_DA0F0TMBIJ0_F0T_Motherboard_J_brd_V01_OCP.brd

R3938  Q_RES  10K 1% CHIP  pkg 0402LF  page 183 : A = PU_OC2_USB_N ; B = P3V3_AUX
PC267_P0_5  Q_CAP  22UF 4V 20% X6S  pkg C0805  page 269 : A = PVCCIN_CPU0 ; B = GND
C1228  Q_CAP  10UF 6.3V 20% X6S  pkg C0402  page 189 : A = P1V05_PCH_AUX ; B = GND

(kicad_pcb
	(version 20260206)
	(generator "pcbnew")
	(generator_version "10.0")
	(general
		(thickness 1.6)
		(legacy_teardrops no)
	)
	(paper "A4")
	(title_block
		(title "03242023_DA0F0TMBIJ0_F0T_Motherboard_J_brd_V01_OCP.brd")
		(comment 1 "Grand Teton / footprints 6087-6089 of 6105")
	)
	(layers
		(0 "F.Cu" signal "TOP")
		(4 "In1.Cu" signal "GND")
		(6 "In2.Cu" signal "IN1")
		(8 "In3.Cu" signal "GND1")
		(10 "In4.Cu" signal "IN2")
		(12 "In5.Cu" signal "GND2")
		(14 "In6.Cu" signal "IN3")
		(16 "In7.Cu" signal "GND3")
		(18 "In8.Cu" signal "VCC")
		(20 "In9.Cu" signal "VCC1")
		(22 "In10.Cu" signal "GND4")
		(24 "In11.Cu" signal "IN4")
		(26 "In12.Cu" signal "GND5")
		(28 "In13.Cu" signal "IN5")
		(30 "In14.Cu" signal "GND6")
		(32 "In15.Cu" signal "IN6")
		(34 "In16.Cu" signal "GND7")
		(2 "B.Cu" signal "BOTTOM")
		(9 "F.Adhes" user "F.Adhesive")
		(11 "B.Adhes" user "B.Adhesive")
		(13 "F.Paste" user "Package Geometry/Pastemask Top")
		(15 "B.Paste" user "Package Geometry/Pastemask Bottom")
		(5 "F.SilkS" user "Ref Des/Silkscreen Top")
		(7 "B.SilkS" user "Ref Des/Silkscreen Bottom")
		(1 "F.Mask" user "Board Geometry/Soldermask Top")
		(3 "B.Mask" user "Board Geometry/Soldermask Bottom")
		(17 "Dwgs.User" user "User.Drawings")
		(19 "Cmts.User" user "User.Comments")
		(21 "Eco1.User" user "User.Eco1")
		(23 "Eco2.User" user "User.Eco2")
		(25 "Edge.Cuts" user "Board Geometry/Outline")
		(27 "Margin" user)
		(31 "F.CrtYd" user "Package Geometry/Place Bound Top")
		(29 "B.CrtYd" user "Package Geometry/Place Bound Bottom")
		(35 "F.Fab" user "Ref Des/Assembly Top")
		(33 "B.Fab" user "Ref Des/Assembly Bottom")
	)
	(footprint ""
		(layer "B.Cu")
		(at 339.27669 -47.512986 180)
		(property "Reference" "C1228"
			(at 0 0 0)
			(layer "B.SilkS")
			(hide yes)
			(effects
				(font
					(size 1.27 1.27)
				)
				(justify mirror)
			)
		)
		(property "Value" ""
			(at 0 0 0)
			(layer "B.Fab")
			(effects
				(font
					(size 1.27 1.27)
				)
				(justify mirror)
			)
		)
		(duplicate_pad_numbers_are_jumpers no)
		(fp_line
			(start 0.7874 0.4064)
			(end 0.7874 -0.4064)
			(stroke
				(width 0.1524)
				(type default)
			)
			(layer "B.SilkS")
		)
		(fp_line
			(start 0.7874 -0.4064)
			(end -0.7874 -0.4064)
			(stroke
				(width 0.1524)
				(type default)
			)
			(layer "B.SilkS")
		)
		(fp_line
			(start -0.7874 0.4064)
			(end 0.7874 0.4064)
			(stroke
				(width 0.1524)
				(type default)
			)
			(layer "B.SilkS")
		)
		(fp_line
			(start -0.7874 -0.4064)
			(end -0.7874 0.4064)
			(stroke
				(width 0.1524)
				(type default)
			)
			(layer "B.SilkS")
		)
		(fp_line
			(start 0.67945 0.3048)
			(end 0.67945 -0.305054)
			(stroke
				(width 0.1)
				(type default)
			)
			(layer "B.Fab")
		)
		(fp_line
			(start 0.67945 -0.305054)
			(end 0.12065 -0.305054)
			(stroke
				(width 0.1)
				(type default)
			)
			(layer "B.Fab")
		)
		(fp_line
			(start 0.12065 0.3048)
			(end 0.67945 0.3048)
			(stroke
				(width 0.1)
				(type default)
			)
			(layer "B.Fab")
		)
		(fp_line
			(start 0.12065 0.2794)
			(end 0.12065 0.3048)
			(stroke
				(width 0.1)
				(type default)
			)
			(layer "B.Fab")
		)
		(fp_line
			(start 0.12065 -0.2794)
			(end -0.12065 -0.2794)
			(stroke
				(width 0.1)
				(type default)
			)
			(layer "B.Fab")
		)
		(fp_line
			(start 0.12065 -0.305054)
			(end 0.12065 -0.2794)
			(stroke
				(width 0.1)
				(type default)
			)
			(layer "B.Fab")
		)
		(fp_line
			(start -0.120396 0.3048)
			(end -0.120396 0.2794)
			(stroke
				(width 0.1)
				(type default)
			)
			(layer "B.Fab")
		)
		(fp_line
			(start -0.120396 0.2794)
			(end 0.12065 0.2794)
			(stroke
				(width 0.1)
				(type default)
			)
			(layer "B.Fab")
		)
		(fp_line
			(start -0.12065 -0.2794)
			(end -0.12065 -0.3048)
			(stroke
				(width 0.1)
				(type default)
			)
			(layer "B.Fab")
		)
		(fp_line
			(start -0.12065 -0.3048)
			(end -0.67945 -0.3048)
			(stroke
				(width 0.1)
				(type default)
			)
			(layer "B.Fab")
		)
		(fp_line
			(start -0.67945 0.3048)
			(end -0.120396 0.3048)
			(stroke
				(width 0.1)
				(type default)
			)
			(layer "B.Fab")
		)
		(fp_line
			(start -0.67945 -0.3048)
			(end -0.67945 0.3048)
			(stroke
				(width 0.1)
				(type default)
			)
			(layer "B.Fab")
		)
		(pad "1" smd circle
			(at 0.40005 0)
			(size 0 0)
			(layers "B.Cu" "B.Mask" "B.Paste")
			(net "P1V05_PCH_AUX")
		)
		(pad "2" smd circle
			(at -0.40005 0)
			(size 0 0)
			(layers "B.Cu" "B.Mask" "B.Paste")
			(net "GND")
		)
	)
	(footprint ""
		(layer "B.Cu")
		(at 374.002046 -328.298048 -90)
		(property "Reference" "PC267_P0_5"
			(at 0 0 90)
			(layer "B.SilkS")
			(hide yes)
			(effects
				(font
					(size 1.27 1.27)
				)
				(justify mirror)
			)
		)
		(property "Value" ""
			(at 0 0 90)
			(layer "B.Fab")
			(effects
				(font
					(size 1.27 1.27)
				)
				(justify mirror)
			)
		)
		(duplicate_pad_numbers_are_jumpers no)
		(fp_line
			(start -1.524 0.762)
			(end 1.524 0.762)
			(stroke
				(width 0.1524)
				(type default)
			)
			(layer "B.SilkS")
		)
		(fp_line
			(start 1.524 0.762)
			(end 1.524 -0.762)
			(stroke
				(width 0.1524)
				(type default)
			)
			(layer "B.SilkS")
		)
		(fp_line
			(start -1.524 -0.762)
			(end -1.524 0.762)
			(stroke
				(width 0.1524)
				(type default)
			)
			(layer "B.SilkS")
		)
		(fp_line
			(start 1.524 -0.762)
			(end -1.524 -0.762)
			(stroke
				(width 0.1524)
				(type default)
			)
			(layer "B.SilkS")
		)
		(fp_line
			(start -1.1049 0.724916)
			(end -1.1049 -0.724916)
			(stroke
				(width 0.1)
				(type default)
			)
			(layer "B.Fab")
		)
		(fp_line
			(start 1.1049 0.724916)
			(end -1.1049 0.724916)
			(stroke
				(width 0.1)
				(type default)
			)
			(layer "B.Fab")
		)
		(fp_line
			(start -1.1049 -0.724916)
			(end 1.1049 -0.724916)
			(stroke
				(width 0.1)
				(type default)
			)
			(layer "B.Fab")
		)
		(fp_line
			(start 1.1049 -0.724916)
			(end 1.1049 0.724916)
			(stroke
				(width 0.1)
				(type default)
			)
			(layer "B.Fab")
		)
		(pad "1" smd rect
			(at 0.889 0 270)
			(size 1.016 1.27)
			(layers "B.Cu" "B.Mask" "B.Paste")
			(net "PVCCIN_CPU0")
		)
		(pad "2" smd rect
			(at -0.889 0 270)
			(size 1.016 1.27)
			(layers "B.Cu" "B.Mask" "B.Paste")
			(net "GND")
		)
	)
	(footprint ""
		(layer "B.Cu")
		(at 343.8779 -35.222688 -90)
		(property "Reference" "R3938"
			(at 0 0 90)
			(layer "B.SilkS")
			(hide yes)
			(effects
				(font
					(size 1.27 1.27)
				)
				(justify mirror)
			)
		)
		(property "Value" ""
			(at 0 0 90)
			(layer "B.Fab")
			(effects
				(font
					(size 1.27 1.27)
				)
				(justify mirror)
			)
		)
		(duplicate_pad_numbers_are_jumpers no)
		(fp_line
			(start -0.7874 0.4064)
			(end 0.7874 0.4064)
			(stroke
				(width 0.1524)
				(type default)
			)
			(layer "B.SilkS")
		)
		(fp_line
			(start 0.7874 0.4064)
			(end 0.7874 -0.4064)
			(stroke
				(width 0.1524)
				(type default)
			)
			(layer "B.SilkS")
		)
		(fp_line
			(start -0.7874 -0.4064)
			(end -0.7874 0.4064)
			(stroke
				(width 0.1524)
				(type default)
			)
			(layer "B.SilkS")
		)
		(fp_line
			(start 0.7874 -0.4064)
			(end -0.7874 -0.4064)
			(stroke
				(width 0.1524)
				(type default)
			)
			(layer "B.SilkS")
		)
		(fp_line
			(start -0.67945 0.3048)
			(end -0.120396 0.3048)
			(stroke
				(width 0.1)
				(type default)
			)
			(layer "B.Fab")
		)
		(fp_line
			(start -0.120396 0.3048)
			(end -0.120396 0.2794)
			(stroke
				(width 0.1)
				(type default)
			)
			(layer "B.Fab")
		)
		(fp_line
			(start 0.12065 0.3048)
			(end 0.67945 0.3048)
			(stroke
				(width 0.1)
				(type default)
			)
			(layer "B.Fab")
		)
		(fp_line
			(start 0.67945 0.3048)
			(end 0.67945 -0.305054)
			(stroke
				(width 0.1)
				(type default)
			)
			(layer "B.Fab")
		)
		(fp_line
			(start -0.120396 0.2794)
			(end 0.12065 0.2794)
			(stroke
				(width 0.1)
				(type default)
			)
			(layer "B.Fab")
		)
		(fp_line
			(start 0.12065 0.2794)
			(end 0.12065 0.3048)
			(stroke
				(width 0.1)
				(type default)
			)
			(layer "B.Fab")
		)
		(fp_line
			(start -0.12065 -0.2794)
			(end -0.12065 -0.3048)
			(stroke
				(width 0.1)
				(type default)
			)
			(layer "B.Fab")
		)
		(fp_line
			(start 0.12065 -0.2794)
			(end -0.12065 -0.2794)
			(stroke
				(width 0.1)
				(type default)
			)
			(layer "B.Fab")
		)
		(fp_line
			(start -0.67945 -0.3048)
			(end -0.67945 0.3048)
			(stroke
				(width 0.1)
				(type default)
			)
			(layer "B.Fab")
		)
		(fp_line
			(start -0.12065 -0.3048)
			(end -0.67945 -0.3048)
			(stroke
				(width 0.1)
				(type default)
			)
			(layer "B.Fab")
		)
		(fp_line
			(start 0.12065 -0.305054)
			(end 0.12065 -0.2794)
			(stroke
				(width 0.1)
				(type default)
			)
			(layer "B.Fab")
		)
		(fp_line
			(start 0.67945 -0.305054)
			(end 0.12065 -0.305054)
			(stroke
				(width 0.1)
				(type default)
			)
			(layer "B.Fab")
		)
		(pad "1" smd circle
			(at 0.40005 0 90)
			(size 0 0)
			(layers "B.Cu" "B.Mask" "B.Paste")
			(net "PU_OC2_USB_N")
		)
		(pad "2" smd circle
			(at -0.40005 0 90)
			(size 0 0)
			(layers "B.Cu" "B.Mask" "B.Paste")
			(net "P3V3_AUX")
		)
	)
)
